(kicad_pcb
	(version 20241229)
	(generator "pcbnew")
	(generator_version "9.0")
	(general
		(thickness 1.552)
		(legacy_teardrops no)
	)
	(paper "A4")
	(title_block
		(date "2023-07-25")
		(rev "1.1.4")
		(comment 9 "footprints 44-48 of 379")
	)
	(layers
		(0 "F.Cu" signal)
		(4 "In1.Cu" signal)
		(6 "In2.Cu" signal)
		(8 "In3.Cu" signal)
		(10 "In4.Cu" signal)
		(12 "In5.Cu" signal)
		(14 "In6.Cu" signal)
		(2 "B.Cu" signal)
		(9 "F.Adhes" user "F.Adhesive")
		(11 "B.Adhes" user "B.Adhesive")
		(13 "F.Paste" user)
		(15 "B.Paste" user)
		(5 "F.SilkS" user "F.Silkscreen")
		(7 "B.SilkS" user "B.Silkscreen")
		(1 "F.Mask" user)
		(3 "B.Mask" user)
		(17 "Dwgs.User" user "User.Drawings")
		(19 "Cmts.User" user "User.Comments")
		(21 "Eco1.User" user "User.Eco1")
		(23 "Eco2.User" user "User.Eco2")
		(25 "Edge.Cuts" user)
		(27 "Margin" user)
		(31 "F.CrtYd" user "F.Courtyard")
		(29 "B.CrtYd" user "B.Courtyard")
		(35 "F.Fab" user)
		(33 "B.Fab" user)
	)
	(footprint "antmicro-footprints:R_0402_1005Metric"
		(layer "F.Cu")
		(at 131.75 116.75 90)
		(descr "Resistor SMD 0402")
		(tags "resistor SMD 0402")
		(property "Reference" "R110"
			(at 0.81 0.28 90)
			(layer "F.SilkS")
			(effects
				(font
					(size 0.65 0.65)
					(thickness 0.15)
				)
				(justify left bottom)
			)
		)
		(property "Value" "R_0R_0402"
			(at 0 1.4 90)
			(layer "F.Fab")
			(hide yes)
			(effects
				(font
					(size 0.7 0.7)
					(thickness 0.15)
				)
				(justify left bottom)
			)
		)
		(property "Datasheet" "https://industrial.panasonic.com/cdbs/www-data/pdf/RDA0000/AOA0000C301.pdf"
			(at 0 0 90)
			(layer "F.Fab")
			(hide yes)
			(effects
				(font
					(size 1.27 1.27)
					(thickness 0.15)
				)
			)
		)
		(property "Description" "SMD Chip Resistor, Jumper, 0 ohm, 100 mW, 0402 [1005 Metric], Thick Film, General Purpose"
			(at 0 0 90)
			(layer "F.Fab")
			(hide yes)
			(effects
				(font
					(size 1.27 1.27)
					(thickness 0.15)
				)
			)
		)
		(property "Author" "Antmicro"
			(at 248.5 -15 0)
			(layer "F.Fab")
			(hide yes)
			(effects
				(font
					(size 1 1)
					(thickness 0.15)
				)
			)
		)
		(property "Current" "1A"
			(at 248.5 -15 0)
			(layer "F.Fab")
			(hide yes)
			(effects
				(font
					(size 1 1)
					(thickness 0.15)
				)
			)
		)
		(property "License" "Apache-2.0"
			(at 248.5 -15 0)
			(layer "F.Fab")
			(hide yes)
			(effects
				(font
					(size 1 1)
					(thickness 0.15)
				)
			)
		)
		(property "MPN" "ERJ2GE0R00X"
			(at 248.5 -15 0)
			(layer "F.Fab")
			(hide yes)
			(effects
				(font
					(size 1 1)
					(thickness 0.15)
				)
			)
		)
		(property "Manufacturer" "Panasonic"
			(at 248.5 -15 0)
			(layer "F.Fab")
			(hide yes)
			(effects
				(font
					(size 1 1)
					(thickness 0.15)
				)
			)
		)
		(property "Tolerance" "~"
			(at 248.5 -15 0)
			(layer "F.Fab")
			(hide yes)
			(effects
				(font
					(size 1 1)
					(thickness 0.15)
				)
			)
		)
		(property "Val" "0R"
			(at 248.5 -15 0)
			(layer "F.Fab")
			(hide yes)
			(effects
				(font
					(size 1 1)
					(thickness 0.15)
				)
			)
		)
		(sheetname "/Peripherals/")
		(sheetfile "peripherals.kicad_sch")
		(attr smd)
		(fp_rect
			(start -0.925 -0.47)
			(end 0.925 0.47)
			(stroke
				(width 0.05)
				(type default)
			)
			(fill no)
			(layer "F.CrtYd")
		)
		(fp_rect
			(start -0.5 -0.25)
			(end 0.5 0.25)
			(stroke
				(width 0.15)
				(type solid)
			)
			(fill no)
			(layer "F.Fab")
		)
		(fp_text user "License: Apache-2.0"
			(at -0.95 5.169 90)
			(layer "F.Fab")
			(effects
				(font
					(size 0.7 0.7)
					(thickness 0.15)
				)
				(justify left bottom)
			)
		)
		(fp_text user "Author: Antmicro"
			(at -0.95 4.169 90)
			(layer "F.Fab")
			(effects
				(font
					(size 0.7 0.7)
					(thickness 0.15)
				)
				(justify left bottom)
			)
		)
		(fp_text user "${REFERENCE}"
			(at -0.95 3.168 90)
			(layer "F.Fab")
			(effects
				(font
					(size 0.7 0.7)
					(thickness 0.15)
				)
				(justify left bottom)
			)
		)
		(pad "1" smd roundrect
			(at -0.48 0 90)
			(size 0.59 0.64)
			(layers "F.Cu" "F.Mask" "F.Paste")
			(roundrect_rratio 0.25)
			(net 302 "Net-(J6-Pad40)")
			(pintype "passive")
		)
		(pad "2" smd roundrect
			(at 0.48 0 90)
			(size 0.59 0.64)
			(layers "F.Cu" "F.Mask" "F.Paste")
			(roundrect_rratio 0.25)
			(net 100 "SCL")
			(pintype "passive")
		)
	)
	(footprint "antmicro-footprints:C_0603_1608Metric"
		(layer "F.Cu")
		(at 142.34 64.8 90)
		(descr "Capacitor SMD 0603")
		(tags "capacitor 0603")
		(property "Reference" "C27"
			(at -0.84 -5.51 90)
			(layer "F.SilkS")
			(effects
				(font
					(size 0.65 0.65)
					(thickness 0.15)
				)
				(justify left bottom)
			)
		)
		(property "Value" "C_22u_0603"
			(at 0 1.6 90)
			(layer "F.Fab")
			(hide yes)
			(effects
				(font
					(size 0.7 0.7)
					(thickness 0.15)
				)
				(justify left bottom)
			)
		)
		(property "Datasheet" "https://www.murata.com/products/productdetail?partno=GRM188R60J226MEA0%23"
			(at 0 0 90)
			(layer "F.Fab")
			(hide yes)
			(effects
				(font
					(size 1.27 1.27)
					(thickness 0.15)
				)
			)
		)
		(property "Description" "SMD Multilayer Ceramic Capacitor, 22 µF, 6.3 V, 0603 [1608 Metric], ± 20%, X5R, GRM Series"
			(at 0 0 90)
			(layer "F.Fab")
			(hide yes)
			(effects
				(font
					(size 1.27 1.27)
					(thickness 0.15)
				)
			)
		)
		(property "Author" "Antmicro"
			(at 207.14 -77.54 0)
			(layer "F.Fab")
			(hide yes)
			(effects
				(font
					(size 1 1)
					(thickness 0.15)
				)
			)
		)
		(property "Dielectric" ""
			(at 207.14 -77.54 0)
			(layer "F.Fab")
			(hide yes)
			(effects
				(font
					(size 1 1)
					(thickness 0.15)
				)
			)
		)
		(property "License" "Apache-2.0"
			(at 207.14 -77.54 0)
			(layer "F.Fab")
			(hide yes)
			(effects
				(font
					(size 1 1)
					(thickness 0.15)
				)
			)
		)
		(property "MPN" "GRM188R60J226MEA0D"
			(at 207.14 -77.54 0)
			(layer "F.Fab")
			(hide yes)
			(effects
				(font
					(size 1 1)
					(thickness 0.15)
				)
			)
		)
		(property "Manufacturer" "Murata"
			(at 207.14 -77.54 0)
			(layer "F.Fab")
			(hide yes)
			(effects
				(font
					(size 1 1)
					(thickness 0.15)
				)
			)
		)
		(property "Val" "22u"
			(at 207.14 -77.54 0)
			(layer "F.Fab")
			(hide yes)
			(effects
				(font
					(size 1 1)
					(thickness 0.15)
				)
			)
		)
		(property "Voltage" ""
			(at 207.14 -77.54 0)
			(layer "F.Fab")
			(hide yes)
			(effects
				(font
					(size 1 1)
					(thickness 0.15)
				)
			)
		)
		(sheetname "/Power Supply/")
		(sheetfile "supply.kicad_sch")
		(attr smd)
		(fp_line
			(start -0.15 -0.4)
			(end 0.15 -0.4)
			(stroke
				(width 0.15)
				(type solid)
			)
			(layer "F.SilkS")
		)
		(fp_line
			(start -0.15 0.4)
			(end 0.15 0.4)
			(stroke
				(width 0.15)
				(type solid)
			)
			(layer "F.SilkS")
		)
		(fp_rect
			(start -1.25 -0.65)
			(end 1.25 0.65)
			(stroke
				(width 0.05)
				(type solid)
			)
			(fill no)
			(layer "F.CrtYd")
		)
		(fp_rect
			(start -0.8 -0.4)
			(end 0.8 0.4)
			(stroke
				(width 0.15)
				(type solid)
			)
			(fill no)
			(layer "F.Fab")
		)
		(fp_text user "License: Apache-2.0"
			(at -1.682 5.895 90)
			(layer "F.Fab")
			(effects
				(font
					(size 0.7 0.7)
					(thickness 0.15)
				)
				(justify left bottom)
			)
		)
		(fp_text user "${REFERENCE}"
			(at -1.682 3.895 90)
			(layer "F.Fab")
			(effects
				(font
					(size 0.7 0.7)
					(thickness 0.15)
				)
				(justify left bottom)
			)
		)
		(fp_text user "Author: Antmicro"
			(at -1.682 4.894 90)
			(layer "F.Fab")
			(effects
				(font
					(size 0.7 0.7)
					(thickness 0.15)
				)
				(justify left bottom)
			)
		)
		(pad "1" smd roundrect
			(at -0.7 0 90)
			(size 0.8 1)
			(layers "F.Cu" "F.Mask" "F.Paste")
			(roundrect_rratio 0.2)
			(net 1 "GND")
			(pintype "passive")
		)
		(pad "2" smd roundrect
			(at 0.7 0 90)
			(size 0.8 1)
			(layers "F.Cu" "F.Mask" "F.Paste")
			(roundrect_rratio 0.2)
			(net 274 "/Power Supply/1V5_OUT")
			(pintype "passive")
		)
	)
	(footprint "antmicro-footprints:C_0603_1608Metric"
		(layer "F.Cu")
		(at 160.59 62.03)
		(descr "Capacitor SMD 0603")
		(tags "capacitor 0603")
		(property "Reference" "C34"
			(at -1.01 -0.49 0)
			(layer "F.SilkS")
			(effects
				(font
					(size 0.65 0.65)
					(thickness 0.15)
				)
				(justify left bottom)
			)
		)
		(property "Value" "C_22u_0603"
			(at 0 1.6 0)
			(layer "F.Fab")
			(hide yes)
			(effects
				(font
					(size 0.7 0.7)
					(thickness 0.15)
				)
				(justify left bottom)
			)
		)
		(property "Datasheet" "https://www.murata.com/products/productdetail?partno=GRM188R60J226MEA0%23"
			(at 0 0 0)
			(layer "F.Fab")
			(hide yes)
			(effects
				(font
					(size 1.27 1.27)
					(thickness 0.15)
				)
			)
		)
		(property "Description" "SMD Multilayer Ceramic Capacitor, 22 µF, 6.3 V, 0603 [1608 Metric], ± 20%, X5R, GRM Series"
			(at 0 0 0)
			(layer "F.Fab")
			(hide yes)
			(effects
				(font
					(size 1.27 1.27)
					(thickness 0.15)
				)
			)
		)
		(property "Author" "Antmicro"
			(at 0 0 0)
			(layer "F.Fab")
			(hide yes)
			(effects
				(font
					(size 1 1)
					(thickness 0.15)
				)
			)
		)
		(property "Dielectric" ""
			(at 0 0 0)
			(layer "F.Fab")
			(hide yes)
			(effects
				(font
					(size 1 1)
					(thickness 0.15)
				)
			)
		)
		(property "License" "Apache-2.0"
			(at 0 0 0)
			(layer "F.Fab")
			(hide yes)
			(effects
				(font
					(size 1 1)
					(thickness 0.15)
				)
			)
		)
		(property "MPN" "GRM188R60J226MEA0D"
			(at 0 0 0)
			(layer "F.Fab")
			(hide yes)
			(effects
				(font
					(size 1 1)
					(thickness 0.15)
				)
			)
		)
		(property "Manufacturer" "Murata"
			(at 0 0 0)
			(layer "F.Fab")
			(hide yes)
			(effects
				(font
					(size 1 1)
					(thickness 0.15)
				)
			)
		)
		(property "Val" "22u"
			(at 0 0 0)
			(layer "F.Fab")
			(hide yes)
			(effects
				(font
					(size 1 1)
					(thickness 0.15)
				)
			)
		)
		(property "Voltage" ""
			(at 0 0 0)
			(layer "F.Fab")
			(hide yes)
			(effects
				(font
					(size 1 1)
					(thickness 0.15)
				)
			)
		)
		(sheetname "/Power Supply/")
		(sheetfile "supply.kicad_sch")
		(attr smd)
		(fp_line
			(start -0.15 -0.4)
			(end 0.15 -0.4)
			(stroke
				(width 0.15)
				(type solid)
			)
			(layer "F.SilkS")
		)
		(fp_line
			(start -0.15 0.4)
			(end 0.15 0.4)
			(stroke
				(width 0.15)
				(type solid)
			)
			(layer "F.SilkS")
		)
		(fp_rect
			(start -1.25 -0.65)
			(end 1.25 0.65)
			(stroke
				(width 0.05)
				(type solid)
			)
			(fill no)
			(layer "F.CrtYd")
		)
		(fp_rect
			(start -0.8 -0.4)
			(end 0.8 0.4)
			(stroke
				(width 0.15)
				(type solid)
			)
			(fill no)
			(layer "F.Fab")
		)
		(fp_text user "Author: Antmicro"
			(at -1.682 4.894 0)
			(layer "F.Fab")
			(effects
				(font
					(size 0.7 0.7)
					(thickness 0.15)
				)
				(justify left bottom)
			)
		)
		(fp_text user "${REFERENCE}"
			(at -1.682 3.895 0)
			(layer "F.Fab")
			(effects
				(font
					(size 0.7 0.7)
					(thickness 0.15)
				)
				(justify left bottom)
			)
		)
		(fp_text user "License: Apache-2.0"
			(at -1.682 5.895 0)
			(layer "F.Fab")
			(effects
				(font
					(size 0.7 0.7)
					(thickness 0.15)
				)
				(justify left bottom)
			)
		)
		(pad "1" smd roundrect
			(at -0.7 0)
			(size 0.8 1)
			(layers "F.Cu" "F.Mask" "F.Paste")
			(roundrect_rratio 0.2)
			(net 1 "GND")
			(pintype "passive")
		)
		(pad "2" smd roundrect
			(at 0.7 0)
			(size 0.8 1)
			(layers "F.Cu" "F.Mask" "F.Paste")
			(roundrect_rratio 0.2)
			(net 275 "/Power Supply/3V3_OUT")
			(pintype "passive")
		)
	)
	(footprint "antmicro-footprints:SOIC-8_3.9x4.9x1.75mm_P1.27mm"
		(layer "F.Cu")
		(at 105.655 94.605 -90)
		(property "Reference" "U18"
			(at 0 -2.85 270)
			(layer "F.SilkS")
			(effects
				(font
					(size 0.7 0.7)
					(thickness 0.15)
				)
				(justify left bottom)
			)
		)
		(property "Value" "W25Q32JVSSIQ"
			(at 0 3.65 270)
			(layer "F.Fab")
			(effects
				(font
					(size 0.7 0.7)
					(thickness 0.15)
				)
				(justify left bottom)
			)
		)
		(property "Author" "Antmicro"
			(at 11.05 200.26 0)
			(layer "F.Fab")
			(hide yes)
			(effects
				(font
					(size 1 1)
					(thickness 0.15)
				)
			)
		)
		(property "License" "Apache-2.0"
			(at 11.05 200.26 0)
			(layer "F.Fab")
			(hide yes)
			(effects
				(font
					(size 1 1)
					(thickness 0.15)
				)
			)
		)
		(property "MPN" "W25Q32JVSSIQ"
			(at 11.05 200.26 0)
			(layer "F.Fab")
			(hide yes)
			(effects
				(font
					(size 1 1)
					(thickness 0.15)
				)
			)
		)
		(property "Manufacturer" "Winbond"
			(at 11.05 200.26 0)
			(layer "F.Fab")
			(hide yes)
			(effects
				(font
					(size 1 1)
					(thickness 0.15)
				)
			)
		)
		(sheetname "/FPGA/")
		(sheetfile "fpga.kicad_sch")
		(attr smd)
		(fp_line
			(start -1.95 2.45)
			(end 1.95 2.45)
			(stroke
				(width 0.15)
				(type solid)
			)
			(layer "F.SilkS")
		)
		(fp_line
			(start -1.95 -2.452)
			(end 1.95 -2.45)
			(stroke
				(width 0.15)
				(type solid)
			)
			(layer "F.SilkS")
		)
		(fp_circle
			(center -2.4 -2.45)
			(end -2.35 -2.4)
			(stroke
				(width 0.15)
				(type solid)
			)
			(fill yes)
			(layer "F.SilkS")
		)
		(fp_rect
			(start -3.625 -2.7)
			(end 3.625 2.7)
			(stroke
				(width 0.05)
				(type solid)
			)
			(fill no)
			(layer "F.CrtYd")
		)
		(fp_line
			(start -1.95 2.45)
			(end -1.95 -1.18)
			(stroke
				(width 0.15)
				(type solid)
			)
			(layer "F.Fab")
		)
		(fp_line
			(start 1.949 2.45)
			(end -1.95 2.45)
			(stroke
				(width 0.15)
				(type solid)
			)
			(layer "F.Fab")
		)
		(fp_line
			(start -1.95 -1.18)
			(end -0.683 -2.452)
			(stroke
				(width 0.15)
				(type solid)
			)
			(layer "F.Fab")
		)
		(fp_line
			(start -0.683 -2.452)
			(end 1.949 -2.452)
			(stroke
				(width 0.15)
				(type solid)
			)
			(layer "F.Fab")
		)
		(fp_line
			(start 1.949 -2.452)
			(end 1.949 2.45)
			(stroke
				(width 0.15)
				(type solid)
			)
			(layer "F.Fab")
		)
		(fp_text user "License: Apache-2.0"
			(at -3.476 5.099 270)
			(layer "F.Fab")
			(effects
				(font
					(size 0.7 0.7)
					(thickness 0.15)
				)
				(justify left bottom)
			)
		)
		(fp_text user "${REFERENCE}"
			(at -3.476 7.099 270)
			(layer "F.Fab")
			(effects
				(font
					(size 0.7 0.7)
					(thickness 0.15)
				)
				(justify left bottom)
			)
		)
		(fp_text user "Author: Antmicro"
			(at -3.476 6.099 270)
			(layer "F.Fab")
			(effects
				(font
					(size 0.7 0.7)
					(thickness 0.15)
				)
				(justify left bottom)
			)
		)
		(pad "1" smd roundrect
			(at -2.714 -1.905)
			(size 0.65 1.525)
			(layers "F.Cu" "F.Mask" "F.Paste")
			(roundrect_rratio 0.25)
			(net 306 "Net-(U18-~{CS})")
			(pinfunction "~{CS}")
			(pintype "input")
		)
		(pad "2" smd roundrect
			(at -2.714 -0.635)
			(size 0.65 1.525)
			(layers "F.Cu" "F.Mask" "F.Paste")
			(roundrect_rratio 0.25)
			(net 301 "Net-(U18-SO{slash}IO1)")
			(pinfunction "SO/IO1")
			(pintype "bidirectional")
		)
		(pad "3" smd roundrect
			(at -2.714 0.632)
			(size 0.65 1.525)
			(layers "F.Cu" "F.Mask" "F.Paste")
			(roundrect_rratio 0.25)
			(net 28 "/FPGA/SPI_DQ2")
			(pinfunction "~{WP}/IO2")
			(pintype "bidirectional")
		)
		(pad "4" smd roundrect
			(at -2.714 1.902)
			(size 0.65 1.525)
			(layers "F.Cu" "F.Mask" "F.Paste")
			(roundrect_rratio 0.25)
			(net 1 "GND")
			(pinfunction "VSS")
			(pintype "power_in")
		)
		(pad "5" smd roundrect
			(at 2.712 1.902)
			(size 0.65 1.525)
			(layers "F.Cu" "F.Mask" "F.Paste")
			(roundrect_rratio 0.25)
			(net 300 "Net-(U18-SI{slash}IO0)")
			(pinfunction "SI/IO0")
			(pintype "bidirectional")
		)
		(pad "6" smd roundrect
			(at 2.712 0.632)
			(size 0.65 1.525)
			(layers "F.Cu" "F.Mask" "F.Paste")
			(roundrect_rratio 0.25)
			(net 303 "Net-(U18-SCLK)")
			(pinfunction "SCLK")
			(pintype "input")
		)
		(pad "7" smd roundrect
			(at 2.712 -0.635)
			(size 0.65 1.525)
			(layers "F.Cu" "F.Mask" "F.Paste")
			(roundrect_rratio 0.25)
			(net 27 "/FPGA/SPI_DQ3")
			(pinfunction "~{HOLD}/IO3")
			(pintype "bidirectional")
		)
		(pad "8" smd roundrect
			(at 2.712 -1.905)
			(size 0.65 1.525)
			(layers "F.Cu" "F.Mask" "F.Paste")
			(roundrect_rratio 0.25)
			(net 2 "+3V3")
			(pinfunction "VCC")
			(pintype "power_in")
		)
	)
	(footprint "antmicro-footprints:R_0402_1005Metric"
		(layer "F.Cu")
		(at 161.49 69.85 90)
		(descr "Resistor SMD 0402")
		(tags "resistor SMD 0402")
		(property "Reference" "R18"
			(at -3.09 -0.36 90)
			(layer "F.SilkS")
			(effects
				(font
					(size 0.65 0.65)
					(thickness 0.15)
				)
				(justify left bottom)
			)
		)
		(property "Value" "R_470R_0402"
			(at 0 1.4 90)
			(layer "F.Fab")
			(hide yes)
			(effects
				(font
					(size 0.7 0.7)
					(thickness 0.15)
				)
				(justify left bottom)
			)
		)
		(property "Datasheet" "https://www.bourns.com/docs/product-datasheets/cr.pdf"
			(at 0 0 90)
			(layer "F.Fab")
			(hide yes)
			(effects
				(font
					(size 1.27 1.27)
					(thickness 0.15)
				)
			)
		)
		(property "Description" "SMD Chip Resistor, 470 ohm, ± 1%, 62.5 mW, 0402 [1005 Metric], Thick Film, General Purpose"
			(at 0 0 90)
			(layer "F.Fab")
			(hide yes)
			(effects
				(font
					(size 1.27 1.27)
					(thickness 0.15)
				)
			)
		)
		(property "Author" "Antmicro"
			(at 231.34 -91.64 0)
			(layer "F.Fab")
			(hide yes)
			(effects
				(font
					(size 1 1)
					(thickness 0.15)
				)
			)
		)
		(property "License" "Apache-2.0"
			(at 231.34 -91.64 0)
			(layer "F.Fab")
			(hide yes)
			(effects
				(font
					(size 1 1)
					(thickness 0.15)
				)
			)
		)
		(property "MPN" "CR0402-FX-4700GLF"
			(at 231.34 -91.64 0)
			(layer "F.Fab")
			(hide yes)
			(effects
				(font
					(size 1 1)
					(thickness 0.15)
				)
			)
		)
		(property "Manufacturer" "Bourns"
			(at 231.34 -91.64 0)
			(layer "F.Fab")
			(hide yes)
			(effects
				(font
					(size 1 1)
					(thickness 0.15)
				)
			)
		)
		(property "Tolerance" "1%"
			(at 231.34 -91.64 0)
			(layer "F.Fab")
			(hide yes)
			(effects
				(font
					(size 1 1)
					(thickness 0.15)
				)
			)
		)
		(property "Val" "470R"
			(at 231.34 -91.64 0)
			(layer "F.Fab")
			(hide yes)
			(effects
				(font
					(size 1 1)
					(thickness 0.15)
				)
			)
		)
		(sheetname "/Power Supply/")
		(sheetfile "supply.kicad_sch")
		(attr smd)
		(fp_rect
			(start -0.925 -0.47)
			(end 0.925 0.47)
			(stroke
				(width 0.05)
				(type default)
			)
			(fill no)
			(layer "F.CrtYd")
		)
		(fp_rect
			(start -0.5 -0.25)
			(end 0.5 0.25)
			(stroke
				(width 0.15)
				(type solid)
			)
			(fill no)
			(layer "F.Fab")
		)
		(fp_text user "License: Apache-2.0"
			(at -0.95 5.169 90)
			(layer "F.Fab")
			(effects
				(font
					(size 0.7 0.7)
					(thickness 0.15)
				)
				(justify left bottom)
			)
		)
		(fp_text user "Author: Antmicro"
			(at -0.95 4.169 90)
			(layer "F.Fab")
			(effects
				(font
					(size 0.7 0.7)
					(thickness 0.15)
				)
				(justify left bottom)
			)
		)
		(fp_text user "${REFERENCE}"
			(at -0.95 3.168 90)
			(layer "F.Fab")
			(effects
				(font
					(size 0.7 0.7)
					(thickness 0.15)
				)
				(justify left bottom)
			)
		)
		(pad "1" smd roundrect
			(at -0.48 0 90)
			(size 0.59 0.64)
			(layers "F.Cu" "F.Mask" "F.Paste")
			(roundrect_rratio 0.25)
			(net 62 "Net-(D2-A)")
			(pintype "passive")
		)
		(pad "2" smd roundrect
			(at 0.48 0 90)
			(size 0.59 0.64)
			(layers "F.Cu" "F.Mask" "F.Paste")
			(roundrect_rratio 0.25)
			(net 14 "+5V")
			(pintype "passive")
		)
	)
)
